(kicad_pcb
	(version 20260206)
	(generator "pcbnew")
	(generator_version "10.0")
	(general
		(thickness 1.6)
		(legacy_teardrops no)
	)
	(paper "A4")
	(title_block
		(title "03242023_DA0F0TMBIJ0_F0T_Motherboard_J_brd_V01_OCP.brd")
		(comment 1 "Grand Teton / footprint 1354 of 6105 (J30), pads 225-291 of 291")
	)
	(layers
		(0 "F.Cu" signal "TOP")
		(4 "In1.Cu" signal "GND")
		(6 "In2.Cu" signal "IN1")
		(8 "In3.Cu" signal "GND1")
		(10 "In4.Cu" signal "IN2")
		(12 "In5.Cu" signal "GND2")
		(14 "In6.Cu" signal "IN3")
		(16 "In7.Cu" signal "GND3")
		(18 "In8.Cu" signal "VCC")
		(20 "In9.Cu" signal "VCC1")
		(22 "In10.Cu" signal "GND4")
		(24 "In11.Cu" signal "IN4")
		(26 "In12.Cu" signal "GND5")
		(28 "In13.Cu" signal "IN5")
		(30 "In14.Cu" signal "GND6")
		(32 "In15.Cu" signal "IN6")
		(34 "In16.Cu" signal "GND7")
		(2 "B.Cu" signal "BOTTOM")
		(9 "F.Adhes" user "F.Adhesive")
		(11 "B.Adhes" user "B.Adhesive")
		(13 "F.Paste" user "Package Geometry/Pastemask Top")
		(15 "B.Paste" user "Package Geometry/Pastemask Bottom")
		(5 "F.SilkS" user "Ref Des/Silkscreen Top")
		(7 "B.SilkS" user "Ref Des/Silkscreen Bottom")
		(1 "F.Mask" user "Board Geometry/Soldermask Top")
		(3 "B.Mask" user "Board Geometry/Soldermask Bottom")
		(17 "Dwgs.User" user "User.Drawings")
		(19 "Cmts.User" user "User.Comments")
		(21 "Eco1.User" user "User.Eco1")
		(23 "Eco2.User" user "User.Eco2")
		(25 "Edge.Cuts" user "Board Geometry/Outline")
		(27 "Margin" user)
		(31 "F.CrtYd" user "Package Geometry/Place Bound Top")
		(29 "B.CrtYd" user "Package Geometry/Place Bound Bottom")
		(35 "F.Fab" user "Ref Des/Assembly Top")
		(33 "B.Fab" user "Ref Des/Assembly Bottom")
	)
	(footprint ""
		(layer "F.Cu")
		(at 191.03848 -258.091686)
		(property "Reference" "J30"
			(at -2.98196 -81.740248 0)
			(unlocked yes)
			(layer "F.SilkS")
			(effects
				(font
					(size 0.7874 0.5842)
					(thickness 0.1524)
				)
				(justify left)
			)
		)
		(property "Value" ""
			(at 0 0 0)
			(layer "F.Fab")
			(effects
				(font
					(size 1.27 1.27)
				)
			)
		)
		(duplicate_pad_numbers_are_jumpers no)
		(pad "225" smd rect
			(at 2.050034 9.774936 270)
			(size 0.519938 1.4986)
			(layers "F.Cu" "F.Mask" "F.Paste")
			(net "M_G_CPU1_SB_CA<5>")
		)
		(pad "226" smd rect
			(at 2.050034 10.625074 270)
			(size 0.519938 1.4986)
			(layers "F.Cu" "F.Mask" "F.Paste")
			(net "GND")
		)
		(pad "227" smd rect
			(at 2.050034 11.474958 270)
			(size 0.519938 1.4986)
			(layers "F.Cu" "F.Mask" "F.Paste")
			(net "M_G_CPU1_SB_PAR")
		)
		(pad "228" smd rect
			(at 2.050034 12.325096 270)
			(size 0.519938 1.4986)
			(layers "F.Cu" "F.Mask" "F.Paste")
			(net "GND")
		)
		(pad "229" smd rect
			(at 2.050034 13.17498 270)
			(size 0.519938 1.4986)
			(layers "F.Cu" "F.Mask" "F.Paste")
			(net "M_G_CPU1_SB_CS_N<3>")
		)
		(pad "230" smd rect
			(at 2.050034 14.025118 270)
			(size 0.519938 1.4986)
			(layers "F.Cu" "F.Mask" "F.Paste")
			(net "GND")
		)
		(pad "231" smd rect
			(at 2.050034 14.875002 270)
			(size 0.519938 1.4986)
			(layers "F.Cu" "F.Mask" "F.Paste")
			(net "TP_CHG_CPU1_DIMM2_FRU_5")
		)
		(pad "232" smd rect
			(at 2.050034 15.724886 270)
			(size 0.519938 1.4986)
			(layers "F.Cu" "F.Mask" "F.Paste")
			(net "TP_CHG_CPU1_DIMM2_FRU_6")
		)
		(pad "233" smd rect
			(at 2.050034 16.575024 270)
			(size 0.519938 1.4986)
			(layers "F.Cu" "F.Mask" "F.Paste")
			(net "GND")
		)
		(pad "234" smd rect
			(at 2.050034 17.424908 270)
			(size 0.519938 1.4986)
			(layers "F.Cu" "F.Mask" "F.Paste")
			(net "M_G_CPU1_SB_CB<6>")
		)
		(pad "235" smd rect
			(at 2.050034 18.275046 270)
			(size 0.519938 1.4986)
			(layers "F.Cu" "F.Mask" "F.Paste")
			(net "GND")
		)
		(pad "236" smd rect
			(at 2.050034 19.12493 270)
			(size 0.519938 1.4986)
			(layers "F.Cu" "F.Mask" "F.Paste")
			(net "M_G_CPU1_SB_CB<7>")
		)
		(pad "237" smd rect
			(at 2.050034 19.975068 270)
			(size 0.519938 1.4986)
			(layers "F.Cu" "F.Mask" "F.Paste")
			(net "GND")
		)
		(pad "238" smd rect
			(at 2.050034 20.824952 270)
			(size 0.519938 1.4986)
			(layers "F.Cu" "F.Mask" "F.Paste")
			(net "M_G_CPU1_SB_DQS_DN<4>")
		)
		(pad "239" smd rect
			(at 2.050034 21.67509 270)
			(size 0.519938 1.4986)
			(layers "F.Cu" "F.Mask" "F.Paste")
			(net "M_G_CPU1_SB_DQS_DP<4>")
		)
		(pad "240" smd rect
			(at 2.050034 22.524974 270)
			(size 0.519938 1.4986)
			(layers "F.Cu" "F.Mask" "F.Paste")
			(net "GND")
		)
		(pad "241" smd rect
			(at 2.050034 23.375112 270)
			(size 0.519938 1.4986)
			(layers "F.Cu" "F.Mask" "F.Paste")
			(net "M_G_CPU1_SB_CB<2>")
		)
		(pad "242" smd rect
			(at 2.050034 24.224996 270)
			(size 0.519938 1.4986)
			(layers "F.Cu" "F.Mask" "F.Paste")
			(net "GND")
		)
		(pad "243" smd rect
			(at 2.050034 25.07488 270)
			(size 0.519938 1.4986)
			(layers "F.Cu" "F.Mask" "F.Paste")
			(net "M_G_CPU1_SB_CB<3>")
		)
		(pad "244" smd rect
			(at 2.050034 25.925018 270)
			(size 0.519938 1.4986)
			(layers "F.Cu" "F.Mask" "F.Paste")
			(net "GND")
		)
		(pad "245" smd rect
			(at 2.050034 26.774902 270)
			(size 0.519938 1.4986)
			(layers "F.Cu" "F.Mask" "F.Paste")
			(net "M_G_CPU1_SB_DQ<2>")
		)
		(pad "246" smd rect
			(at 2.050034 27.62504 270)
			(size 0.519938 1.4986)
			(layers "F.Cu" "F.Mask" "F.Paste")
			(net "GND")
		)
		(pad "247" smd rect
			(at 2.050034 28.474924 270)
			(size 0.519938 1.4986)
			(layers "F.Cu" "F.Mask" "F.Paste")
			(net "M_G_CPU1_SB_DQ<3>")
		)
		(pad "248" smd rect
			(at 2.050034 29.325062 270)
			(size 0.519938 1.4986)
			(layers "F.Cu" "F.Mask" "F.Paste")
			(net "GND")
		)
		(pad "249" smd rect
			(at 2.050034 30.174946 270)
			(size 0.519938 1.4986)
			(layers "F.Cu" "F.Mask" "F.Paste")
			(net "M_G_CPU1_SB_DQS_DN<5>")
		)
		(pad "250" smd rect
			(at 2.050034 31.025084 270)
			(size 0.519938 1.4986)
			(layers "F.Cu" "F.Mask" "F.Paste")
			(net "M_G_CPU1_SB_DQS_DP<5>")
		)
		(pad "251" smd rect
			(at 2.050034 31.874968 270)
			(size 0.519938 1.4986)
			(layers "F.Cu" "F.Mask" "F.Paste")
			(net "GND")
		)
		(pad "252" smd rect
			(at 2.050034 32.725106 270)
			(size 0.519938 1.4986)
			(layers "F.Cu" "F.Mask" "F.Paste")
			(net "M_G_CPU1_SB_DQ<6>")
		)
		(pad "253" smd rect
			(at 2.050034 33.57499 270)
			(size 0.519938 1.4986)
			(layers "F.Cu" "F.Mask" "F.Paste")
			(net "GND")
		)
		(pad "254" smd rect
			(at 2.050034 34.425128 270)
			(size 0.519938 1.4986)
			(layers "F.Cu" "F.Mask" "F.Paste")
			(net "M_G_CPU1_SB_DQ<7>")
		)
		(pad "255" smd rect
			(at 2.050034 35.275012 270)
			(size 0.519938 1.4986)
			(layers "F.Cu" "F.Mask" "F.Paste")
			(net "GND")
		)
		(pad "256" smd rect
			(at 2.050034 36.124896 270)
			(size 0.519938 1.4986)
			(layers "F.Cu" "F.Mask" "F.Paste")
			(net "M_G_CPU1_SB_DQ<10>")
		)
		(pad "257" smd rect
			(at 2.050034 36.975034 270)
			(size 0.519938 1.4986)
			(layers "F.Cu" "F.Mask" "F.Paste")
			(net "GND")
		)
		(pad "258" smd rect
			(at 2.050034 37.824918 270)
			(size 0.519938 1.4986)
			(layers "F.Cu" "F.Mask" "F.Paste")
			(net "M_G_CPU1_SB_DQ<11>")
		)
		(pad "259" smd rect
			(at 2.050034 38.675056 270)
			(size 0.519938 1.4986)
			(layers "F.Cu" "F.Mask" "F.Paste")
			(net "GND")
		)
		(pad "260" smd rect
			(at 2.050034 39.52494 270)
			(size 0.519938 1.4986)
			(layers "F.Cu" "F.Mask" "F.Paste")
			(net "M_G_CPU1_SB_DQS_DN<6>")
		)
		(pad "261" smd rect
			(at 2.050034 40.375078 270)
			(size 0.519938 1.4986)
			(layers "F.Cu" "F.Mask" "F.Paste")
			(net "M_G_CPU1_SB_DQS_DP<6>")
		)
		(pad "262" smd rect
			(at 2.050034 41.224962 270)
			(size 0.519938 1.4986)
			(layers "F.Cu" "F.Mask" "F.Paste")
			(net "GND")
		)
		(pad "263" smd rect
			(at 2.050034 42.0751 270)
			(size 0.519938 1.4986)
			(layers "F.Cu" "F.Mask" "F.Paste")
			(net "M_G_CPU1_SB_DQ<14>")
		)
		(pad "264" smd rect
			(at 2.050034 42.924984 270)
			(size 0.519938 1.4986)
			(layers "F.Cu" "F.Mask" "F.Paste")
			(net "GND")
		)
		(pad "265" smd rect
			(at 2.050034 43.775122 270)
			(size 0.519938 1.4986)
			(layers "F.Cu" "F.Mask" "F.Paste")
			(net "M_G_CPU1_SB_DQ<15>")
		)
		(pad "266" smd rect
			(at 2.050034 44.625006 270)
			(size 0.519938 1.4986)
			(layers "F.Cu" "F.Mask" "F.Paste")
			(net "GND")
		)
		(pad "267" smd rect
			(at 2.050034 45.47489 270)
			(size 0.519938 1.4986)
			(layers "F.Cu" "F.Mask" "F.Paste")
			(net "M_G_CPU1_SB_DQ<18>")
		)
		(pad "268" smd rect
			(at 2.050034 46.325028 270)
			(size 0.519938 1.4986)
			(layers "F.Cu" "F.Mask" "F.Paste")
			(net "GND")
		)
		(pad "269" smd rect
			(at 2.050034 47.174912 270)
			(size 0.519938 1.4986)
			(layers "F.Cu" "F.Mask" "F.Paste")
			(net "M_G_CPU1_SB_DQ<19>")
		)
		(pad "270" smd rect
			(at 2.050034 48.02505 270)
			(size 0.519938 1.4986)
			(layers "F.Cu" "F.Mask" "F.Paste")
			(net "GND")
		)
		(pad "271" smd rect
			(at 2.050034 48.874934 270)
			(size 0.519938 1.4986)
			(layers "F.Cu" "F.Mask" "F.Paste")
			(net "M_G_CPU1_SB_DQS_DN<7>")
		)
		(pad "272" smd rect
			(at 2.050034 49.725072 270)
			(size 0.519938 1.4986)
			(layers "F.Cu" "F.Mask" "F.Paste")
			(net "M_G_CPU1_SB_DQS_DP<7>")
		)
		(pad "273" smd rect
			(at 2.050034 50.574956 270)
			(size 0.519938 1.4986)
			(layers "F.Cu" "F.Mask" "F.Paste")
			(net "GND")
		)
		(pad "274" smd rect
			(at 2.050034 51.425094 270)
			(size 0.519938 1.4986)
			(layers "F.Cu" "F.Mask" "F.Paste")
			(net "M_G_CPU1_SB_DQ<22>")
		)
		(pad "275" smd rect
			(at 2.050034 52.274978 270)
			(size 0.519938 1.4986)
			(layers "F.Cu" "F.Mask" "F.Paste")
			(net "GND")
		)
		(pad "276" smd rect
			(at 2.050034 53.125116 270)
			(size 0.519938 1.4986)
			(layers "F.Cu" "F.Mask" "F.Paste")
			(net "M_G_CPU1_SB_DQ<23>")
		)
		(pad "277" smd rect
			(at 2.050034 53.975 270)
			(size 0.519938 1.4986)
			(layers "F.Cu" "F.Mask" "F.Paste")
			(net "GND")
		)
		(pad "278" smd rect
			(at 2.050034 54.824884 270)
			(size 0.519938 1.4986)
			(layers "F.Cu" "F.Mask" "F.Paste")
			(net "M_G_CPU1_SB_DQ<26>")
		)
		(pad "279" smd rect
			(at 2.050034 55.675022 270)
			(size 0.519938 1.4986)
			(layers "F.Cu" "F.Mask" "F.Paste")
			(net "GND")
		)
		(pad "280" smd rect
			(at 2.050034 56.524906 270)
			(size 0.519938 1.4986)
			(layers "F.Cu" "F.Mask" "F.Paste")
			(net "M_G_CPU1_SB_DQ<27>")
		)
		(pad "281" smd rect
			(at 2.050034 57.375044 270)
			(size 0.519938 1.4986)
			(layers "F.Cu" "F.Mask" "F.Paste")
			(net "GND")
		)
		(pad "282" smd rect
			(at 2.050034 58.224928 270)
			(size 0.519938 1.4986)
			(layers "F.Cu" "F.Mask" "F.Paste")
			(net "M_G_CPU1_SB_DQS_DN<8>")
		)
		(pad "283" smd rect
			(at 2.050034 59.075066 270)
			(size 0.519938 1.4986)
			(layers "F.Cu" "F.Mask" "F.Paste")
			(net "M_G_CPU1_SB_DQS_DP<8>")
		)
		(pad "284" smd rect
			(at 2.050034 59.92495 270)
			(size 0.519938 1.4986)
			(layers "F.Cu" "F.Mask" "F.Paste")
			(net "GND")
		)
		(pad "285" smd rect
			(at 2.050034 60.775088 270)
			(size 0.519938 1.4986)
			(layers "F.Cu" "F.Mask" "F.Paste")
			(net "M_G_CPU1_SB_DQ<30>")
		)
		(pad "286" smd rect
			(at 2.050034 61.624972 270)
			(size 0.519938 1.4986)
			(layers "F.Cu" "F.Mask" "F.Paste")
			(net "GND")
		)
		(pad "287" smd rect
			(at 2.050034 62.47511 270)
			(size 0.519938 1.4986)
			(layers "F.Cu" "F.Mask" "F.Paste")
			(net "M_G_CPU1_SB_DQ<31>")
		)
		(pad "288" smd rect
			(at 2.050034 63.324994 270)
			(size 0.519938 1.4986)
			(layers "F.Cu" "F.Mask" "F.Paste")
			(net "GND")
		)
		(pad "G1" thru_hole oval
			(at 0 -68.97497)
			(size 2.8194 1.5748)
			(drill oval 2.4384 1.1938)
			(layers "*.Cu" "*.Mask")
			(remove_unused_layers no)
			(net "GND")
			(clearance 0.127)
			(thermal_gap 0.127)
		)
		(pad "G2" thru_hole oval
			(at 0 3.875024)
			(size 2.8194 1.5748)
			(drill oval 2.4384 1.1938)
			(layers "*.Cu" "*.Mask")
			(remove_unused_layers no)
			(net "GND")
			(clearance 0.127)
			(thermal_gap 0.127)
		)
		(pad "G3" thru_hole oval
			(at 0 68.97497)
			(size 2.8194 1.5748)
			(drill oval 2.4384 1.1938)
			(layers "*.Cu" "*.Mask")
			(remove_unused_layers no)
			(net "GND")
			(clearance 0.127)
			(thermal_gap 0.127)
		)
	)
)
